(kicad_pcb
	(version 20241229)
	(generator "pcbnew")
	(generator_version "9.0")
	(general
		(thickness 1.62)
		(legacy_teardrops no)
	)
	(paper "A3")
	(title_block
		(title "COM Express 7 Baseboard")
		(date "2025-02-04")
		(rev "1.1.2")
		(company "Antmicro Ltd")
		(comment 1 "www.antmicro.com")
		(comment 9 "footprint 489 of 802 (J12), pads 246-285 of 450")
	)
	(layers
		(0 "F.Cu" signal)
		(4 "In1.Cu" signal)
		(6 "In2.Cu" signal)
		(8 "In3.Cu" signal)
		(10 "In4.Cu" signal)
		(12 "In5.Cu" signal)
		(14 "In6.Cu" signal)
		(2 "B.Cu" signal)
		(9 "F.Adhes" user "F.Adhesive")
		(11 "B.Adhes" user "B.Adhesive")
		(13 "F.Paste" user)
		(15 "B.Paste" user)
		(5 "F.SilkS" user "F.Silkscreen")
		(7 "B.SilkS" user "B.Silkscreen")
		(1 "F.Mask" user)
		(3 "B.Mask" user)
		(17 "Dwgs.User" user "User.Drawings")
		(19 "Cmts.User" user "User.Comments")
		(21 "Eco1.User" user "User.Eco1")
		(23 "Eco2.User" user "User.Eco2")
		(25 "Edge.Cuts" user)
		(27 "Margin" user)
		(31 "F.CrtYd" user "F.Courtyard")
		(29 "B.CrtYd" user "B.Courtyard")
		(35 "F.Fab" user)
		(33 "B.Fab" user)
	)
	(footprint "antmicro-footprints:EPT_401-51501-51"
		(layer "F.Cu")
		(at 203.275 159.81)
		(property "Reference" "J12"
			(at 30.975 -10.45 0)
			(layer "F.SilkS")
			(effects
				(font
					(size 0.7 0.7)
					(thickness 0.15)
				)
				(justify right top)
			)
		)
		(property "Value" "Plug_Bus_CE7_EPT_401-51501-51"
			(at -3.225 52.665 0)
			(layer "F.Fab")
			(hide yes)
			(effects
				(font
					(size 0.7 0.7)
					(thickness 0.15)
				)
				(justify left top)
			)
		)
		(property "Datasheet" "https://www.farnell.com/datasheets/1905093.pdf"
			(at 0 0 0)
			(layer "F.Fab")
			(hide yes)
			(effects
				(font
					(size 1.27 1.27)
					(thickness 0.15)
				)
			)
		)
		(property "Author" "Antmicro"
			(at 406.55 319.62 0)
			(layer "F.Fab")
			(hide yes)
			(effects
				(font
					(size 1 1)
					(thickness 0.15)
				)
			)
		)
		(property "License" "Apache-2.0"
			(at 406.55 319.62 0)
			(layer "F.Fab")
			(hide yes)
			(effects
				(font
					(size 1 1)
					(thickness 0.15)
				)
			)
		)
		(property "MPN" "401-51501-51"
			(at 406.55 319.62 0)
			(layer "F.Fab")
			(hide yes)
			(effects
				(font
					(size 1 1)
					(thickness 0.15)
				)
			)
		)
		(property "Manufacturer" "ept"
			(at 406.55 319.62 0)
			(layer "F.Fab")
			(hide yes)
			(effects
				(font
					(size 1 1)
					(thickness 0.15)
				)
			)
		)
		(sheetname "Com Express 7 Interfaces")
		(sheetfile "com_express_7_interfaces.kicad_sch")
		(attr smd)
		(pad "C21" smd rect
			(at -17.25 -3.125)
			(size 0.3 1.75)
			(layers "F.Cu" "F.Mask" "F.Paste")
			(net 1 "GND")
			(pinfunction "GND(FIXED)")
			(pintype "passive")
			(teardrops
				(best_length_ratio 0.2)
				(max_length 1)
				(best_width_ratio 0.9)
				(max_width 2)
				(curved_edges yes)
				(filter_ratio 0.9)
				(enabled yes)
				(allow_two_segments yes)
				(prefer_zone_connections yes)
			)
		)
		(pad "C22" smd rect
			(at -16.75 -3.125)
			(size 0.3 1.75)
			(layers "F.Cu" "F.Mask" "F.Paste")
			(net 412 "unconnected-(J12O-PCIE_RX7+-PadC22)")
			(pinfunction "PCIE_RX7+")
			(pintype "input+no_connect")
			(teardrops
				(best_length_ratio 0.2)
				(max_length 1)
				(best_width_ratio 0.9)
				(max_width 2)
				(curved_edges yes)
				(filter_ratio 0.9)
				(enabled yes)
				(allow_two_segments yes)
				(prefer_zone_connections yes)
			)
		)
		(pad "C23" smd rect
			(at -16.25 -3.125)
			(size 0.3 1.75)
			(layers "F.Cu" "F.Mask" "F.Paste")
			(net 413 "unconnected-(J12O-PCIE_RX7--PadC23)")
			(pinfunction "PCIE_RX7-")
			(pintype "input+no_connect")
			(teardrops
				(best_length_ratio 0.2)
				(max_length 1)
				(best_width_ratio 0.9)
				(max_width 2)
				(curved_edges yes)
				(filter_ratio 0.9)
				(enabled yes)
				(allow_two_segments yes)
				(prefer_zone_connections yes)
			)
		)
		(pad "C24" smd rect
			(at -15.75 -3.125)
			(size 0.3 1.75)
			(layers "F.Cu" "F.Mask" "F.Paste")
			(net 414 "unconnected-(J12K-10G_INT2-PadC24)")
			(pinfunction "10G_INT2")
			(pintype "input+no_connect")
			(teardrops
				(best_length_ratio 0.2)
				(max_length 1)
				(best_width_ratio 0.9)
				(max_width 2)
				(curved_edges yes)
				(filter_ratio 0.9)
				(enabled yes)
				(allow_two_segments yes)
				(prefer_zone_connections yes)
			)
		)
		(pad "C25" smd rect
			(at -15.25 -3.125)
			(size 0.3 1.75)
			(layers "F.Cu" "F.Mask" "F.Paste")
			(net 1 "GND")
			(pinfunction "GND")
			(pintype "passive")
			(teardrops
				(best_length_ratio 0.2)
				(max_length 1)
				(best_width_ratio 0.9)
				(max_width 2)
				(curved_edges yes)
				(filter_ratio 0.9)
				(enabled yes)
				(allow_two_segments yes)
				(prefer_zone_connections yes)
			)
		)
		(pad "C26" smd rect
			(at -14.75 -3.125)
			(size 0.3 1.75)
			(layers "F.Cu" "F.Mask" "F.Paste")
			(net 415 "unconnected-(J12K-10G_KR_RX3+-PadC26)")
			(pinfunction "10G_KR_RX3+")
			(pintype "input+no_connect")
			(teardrops
				(best_length_ratio 0.2)
				(max_length 1)
				(best_width_ratio 0.9)
				(max_width 2)
				(curved_edges yes)
				(filter_ratio 0.9)
				(enabled yes)
				(allow_two_segments yes)
				(prefer_zone_connections yes)
			)
		)
		(pad "C27" smd rect
			(at -14.25 -3.125)
			(size 0.3 1.75)
			(layers "F.Cu" "F.Mask" "F.Paste")
			(net 416 "unconnected-(J12K-10G_KR_RX3--PadC27)")
			(pinfunction "10G_KR_RX3-")
			(pintype "input+no_connect")
			(teardrops
				(best_length_ratio 0.2)
				(max_length 1)
				(best_width_ratio 0.9)
				(max_width 2)
				(curved_edges yes)
				(filter_ratio 0.9)
				(enabled yes)
				(allow_two_segments yes)
				(prefer_zone_connections yes)
			)
		)
		(pad "C28" smd rect
			(at -13.75 -3.125)
			(size 0.3 1.75)
			(layers "F.Cu" "F.Mask" "F.Paste")
			(net 1 "GND")
			(pinfunction "GND")
			(pintype "passive")
			(teardrops
				(best_length_ratio 0.2)
				(max_length 1)
				(best_width_ratio 0.9)
				(max_width 2)
				(curved_edges yes)
				(filter_ratio 0.9)
				(enabled yes)
				(allow_two_segments yes)
				(prefer_zone_connections yes)
			)
		)
		(pad "C29" smd rect
			(at -13.25 -3.125)
			(size 0.3 1.75)
			(layers "F.Cu" "F.Mask" "F.Paste")
			(net 417 "unconnected-(J12K-10G_KR_RX2+-PadC29)")
			(pinfunction "10G_KR_RX2+")
			(pintype "input+no_connect")
			(teardrops
				(best_length_ratio 0.2)
				(max_length 1)
				(best_width_ratio 0.9)
				(max_width 2)
				(curved_edges yes)
				(filter_ratio 0.9)
				(enabled yes)
				(allow_two_segments yes)
				(prefer_zone_connections yes)
			)
		)
		(pad "C30" smd rect
			(at -12.75 -3.125)
			(size 0.3 1.75)
			(layers "F.Cu" "F.Mask" "F.Paste")
			(net 418 "unconnected-(J12K-10G_KR_RX2--PadC30)")
			(pinfunction "10G_KR_RX2-")
			(pintype "input+no_connect")
			(teardrops
				(best_length_ratio 0.2)
				(max_length 1)
				(best_width_ratio 0.9)
				(max_width 2)
				(curved_edges yes)
				(filter_ratio 0.9)
				(enabled yes)
				(allow_two_segments yes)
				(prefer_zone_connections yes)
			)
		)
		(pad "C31" smd rect
			(at -12.25 -3.125)
			(size 0.3 1.75)
			(layers "F.Cu" "F.Mask" "F.Paste")
			(net 1 "GND")
			(pinfunction "GND(FIXED)")
			(pintype "passive")
			(teardrops
				(best_length_ratio 0.2)
				(max_length 1)
				(best_width_ratio 0.9)
				(max_width 2)
				(curved_edges yes)
				(filter_ratio 0.9)
				(enabled yes)
				(allow_two_segments yes)
				(prefer_zone_connections yes)
			)
		)
		(pad "C32" smd rect
			(at -11.75 -3.125)
			(size 0.3 1.75)
			(layers "F.Cu" "F.Mask" "F.Paste")
			(net 419 "unconnected-(J12K-10G_SFP_SDA3-PadC32)")
			(pinfunction "10G_SFP_SDA3")
			(pintype "open_collector+no_connect")
			(teardrops
				(best_length_ratio 0.2)
				(max_length 1)
				(best_width_ratio 0.9)
				(max_width 2)
				(curved_edges yes)
				(filter_ratio 0.9)
				(enabled yes)
				(allow_two_segments yes)
				(prefer_zone_connections yes)
			)
		)
		(pad "C33" smd rect
			(at -11.25 -3.125)
			(size 0.3 1.75)
			(layers "F.Cu" "F.Mask" "F.Paste")
			(net 420 "unconnected-(J12K-10G_SFP_SDA2-PadC33)")
			(pinfunction "10G_SFP_SDA2")
			(pintype "open_collector+no_connect")
			(teardrops
				(best_length_ratio 0.2)
				(max_length 1)
				(best_width_ratio 0.9)
				(max_width 2)
				(curved_edges yes)
				(filter_ratio 0.9)
				(enabled yes)
				(allow_two_segments yes)
				(prefer_zone_connections yes)
			)
		)
		(pad "C34" smd rect
			(at -10.75 -3.125)
			(size 0.3 1.75)
			(layers "F.Cu" "F.Mask" "F.Paste")
			(net 421 "unconnected-(J12K-10G_PHY_RST_23-PadC34)")
			(pinfunction "10G_PHY_RST_23")
			(pintype "output+no_connect")
			(teardrops
				(best_length_ratio 0.2)
				(max_length 1)
				(best_width_ratio 0.9)
				(max_width 2)
				(curved_edges yes)
				(filter_ratio 0.9)
				(enabled yes)
				(allow_two_segments yes)
				(prefer_zone_connections yes)
			)
		)
		(pad "C35" smd rect
			(at -10.25 -3.125)
			(size 0.3 1.75)
			(layers "F.Cu" "F.Mask" "F.Paste")
			(net 142 "/2xSFP+/PHY0_{RESET}")
			(pinfunction "10G_PHY_RST_01")
			(pintype "output")
			(teardrops
				(best_length_ratio 0.2)
				(max_length 1)
				(best_width_ratio 0.9)
				(max_width 2)
				(curved_edges yes)
				(filter_ratio 0.9)
				(enabled yes)
				(allow_two_segments yes)
				(prefer_zone_connections yes)
			)
		)
		(pad "C36" smd rect
			(at -9.75 -3.125)
			(size 0.3 1.75)
			(layers "F.Cu" "F.Mask" "F.Paste")
			(net 422 "/2xSFP+/I2C_{LED}.SDA")
			(pinfunction "10G_LED_SDA")
			(pintype "open_collector")
			(teardrops
				(best_length_ratio 0.2)
				(max_length 1)
				(best_width_ratio 0.9)
				(max_width 2)
				(curved_edges yes)
				(filter_ratio 0.9)
				(enabled yes)
				(allow_two_segments yes)
				(prefer_zone_connections yes)
			)
		)
		(pad "C37" smd rect
			(at -9.25 -3.125)
			(size 0.3 1.75)
			(layers "F.Cu" "F.Mask" "F.Paste")
			(net 423 "/2xSFP+/I2C_{LED}.SCL")
			(pinfunction "10G_LED_SCL")
			(pintype "open_collector")
			(teardrops
				(best_length_ratio 0.2)
				(max_length 1)
				(best_width_ratio 0.9)
				(max_width 2)
				(curved_edges yes)
				(filter_ratio 0.9)
				(enabled yes)
				(allow_two_segments yes)
				(prefer_zone_connections yes)
			)
		)
		(pad "C38" smd rect
			(at -8.75 -3.125)
			(size 0.3 1.75)
			(layers "F.Cu" "F.Mask" "F.Paste")
			(net 424 "/2xSFP+/I2C_{SFP1}.SDA")
			(pinfunction "10G_SFP_SDA1")
			(pintype "open_collector")
			(teardrops
				(best_length_ratio 0.2)
				(max_length 1)
				(best_width_ratio 0.9)
				(max_width 2)
				(curved_edges yes)
				(filter_ratio 0.9)
				(enabled yes)
				(allow_two_segments yes)
				(prefer_zone_connections yes)
			)
		)
		(pad "C39" smd rect
			(at -8.25 -3.125)
			(size 0.3 1.75)
			(layers "F.Cu" "F.Mask" "F.Paste")
			(net 425 "/2xSFP+/I2C_{SFP0}.SDA")
			(pinfunction "10G_SFP_SDA0")
			(pintype "open_collector")
			(teardrops
				(best_length_ratio 0.2)
				(max_length 1)
				(best_width_ratio 0.9)
				(max_width 2)
				(curved_edges yes)
				(filter_ratio 0.9)
				(enabled yes)
				(allow_two_segments yes)
				(prefer_zone_connections yes)
			)
		)
		(pad "C40" smd rect
			(at -7.75 -3.125)
			(size 0.3 1.75)
			(layers "F.Cu" "F.Mask" "F.Paste")
			(net 426 "Net-(J12K-10G_SDP0)")
			(pinfunction "10G_SDP0")
			(pintype "bidirectional")
			(teardrops
				(best_length_ratio 0.2)
				(max_length 1)
				(best_width_ratio 0.9)
				(max_width 2)
				(curved_edges yes)
				(filter_ratio 0.9)
				(enabled yes)
				(allow_two_segments yes)
				(prefer_zone_connections yes)
			)
		)
		(pad "C41" smd rect
			(at -7.25 -3.125)
			(size 0.3 1.75)
			(layers "F.Cu" "F.Mask" "F.Paste")
			(net 1 "GND")
			(pinfunction "GND(FIXED)")
			(pintype "passive")
			(teardrops
				(best_length_ratio 0.2)
				(max_length 1)
				(best_width_ratio 0.9)
				(max_width 2)
				(curved_edges yes)
				(filter_ratio 0.9)
				(enabled yes)
				(allow_two_segments yes)
				(prefer_zone_connections yes)
			)
		)
		(pad "C42" smd rect
			(at -6.75 -3.125)
			(size 0.3 1.75)
			(layers "F.Cu" "F.Mask" "F.Paste")
			(net 427 "/2xSFP+/10GKR_SFP1.RX+")
			(pinfunction "10G_KR_RX1+")
			(pintype "input")
			(teardrops
				(best_length_ratio 0.2)
				(max_length 1)
				(best_width_ratio 0.9)
				(max_width 2)
				(curved_edges yes)
				(filter_ratio 0.9)
				(enabled yes)
				(allow_two_segments yes)
				(prefer_zone_connections yes)
			)
		)
		(pad "C43" smd rect
			(at -6.25 -3.125)
			(size 0.3 1.75)
			(layers "F.Cu" "F.Mask" "F.Paste")
			(net 428 "/2xSFP+/10GKR_SFP1.RX-")
			(pinfunction "10G_KR_RX1-")
			(pintype "input")
			(teardrops
				(best_length_ratio 0.2)
				(max_length 1)
				(best_width_ratio 0.9)
				(max_width 2)
				(curved_edges yes)
				(filter_ratio 0.9)
				(enabled yes)
				(allow_two_segments yes)
				(prefer_zone_connections yes)
			)
		)
		(pad "C44" smd rect
			(at -5.75 -3.125)
			(size 0.3 1.75)
			(layers "F.Cu" "F.Mask" "F.Paste")
			(net 1 "GND")
			(pinfunction "GND")
			(pintype "passive")
			(teardrops
				(best_length_ratio 0.2)
				(max_length 1)
				(best_width_ratio 0.9)
				(max_width 2)
				(curved_edges yes)
				(filter_ratio 0.9)
				(enabled yes)
				(allow_two_segments yes)
				(prefer_zone_connections yes)
			)
		)
		(pad "C45" smd rect
			(at -5.25 -3.125)
			(size 0.3 1.75)
			(layers "F.Cu" "F.Mask" "F.Paste")
			(net 429 "/2xSFP+/MDIO1.MDC")
			(pinfunction "10G_PHY_MDC_SCL1")
			(pintype "open_collector")
			(teardrops
				(best_length_ratio 0.2)
				(max_length 1)
				(best_width_ratio 0.9)
				(max_width 2)
				(curved_edges yes)
				(filter_ratio 0.9)
				(enabled yes)
				(allow_two_segments yes)
				(prefer_zone_connections yes)
			)
		)
		(pad "C46" smd rect
			(at -4.75 -3.125)
			(size 0.3 1.75)
			(layers "F.Cu" "F.Mask" "F.Paste")
			(net 430 "/2xSFP+/MDIO0.MDC")
			(pinfunction "10G_PHY_MDC_SCL0")
			(pintype "open_collector")
			(teardrops
				(best_length_ratio 0.2)
				(max_length 1)
				(best_width_ratio 0.9)
				(max_width 2)
				(curved_edges yes)
				(filter_ratio 0.9)
				(enabled yes)
				(allow_two_segments yes)
				(prefer_zone_connections yes)
			)
		)
		(pad "C47" smd rect
			(at -4.25 -3.125)
			(size 0.3 1.75)
			(layers "F.Cu" "F.Mask" "F.Paste")
			(net 431 "/2xSFP+/MOD0_ABS")
			(pinfunction "10G_INT0")
			(pintype "input")
			(teardrops
				(best_length_ratio 0.2)
				(max_length 1)
				(best_width_ratio 0.9)
				(max_width 2)
				(curved_edges yes)
				(filter_ratio 0.9)
				(enabled yes)
				(allow_two_segments yes)
				(prefer_zone_connections yes)
			)
		)
		(pad "C48" smd rect
			(at -3.75 -3.125)
			(size 0.3 1.75)
			(layers "F.Cu" "F.Mask" "F.Paste")
			(net 1 "GND")
			(pinfunction "GND")
			(pintype "passive")
			(teardrops
				(best_length_ratio 0.2)
				(max_length 1)
				(best_width_ratio 0.9)
				(max_width 2)
				(curved_edges yes)
				(filter_ratio 0.9)
				(enabled yes)
				(allow_two_segments yes)
				(prefer_zone_connections yes)
			)
		)
		(pad "C49" smd rect
			(at -3.25 -3.125)
			(size 0.3 1.75)
			(layers "F.Cu" "F.Mask" "F.Paste")
			(net 432 "/2xSFP+/10GKR_SFP0.RX+")
			(pinfunction "10G_KR_RX0+")
			(pintype "input")
			(teardrops
				(best_length_ratio 0.2)
				(max_length 1)
				(best_width_ratio 0.9)
				(max_width 2)
				(curved_edges yes)
				(filter_ratio 0.9)
				(enabled yes)
				(allow_two_segments yes)
				(prefer_zone_connections yes)
			)
		)
		(pad "C50" smd rect
			(at -2.75 -3.125)
			(size 0.3 1.75)
			(layers "F.Cu" "F.Mask" "F.Paste")
			(net 433 "/2xSFP+/10GKR_SFP0.RX-")
			(pinfunction "10G_KR_RX0-")
			(pintype "input")
			(teardrops
				(best_length_ratio 0.2)
				(max_length 1)
				(best_width_ratio 0.9)
				(max_width 2)
				(curved_edges yes)
				(filter_ratio 0.9)
				(enabled yes)
				(allow_two_segments yes)
				(prefer_zone_connections yes)
			)
		)
		(pad "C51" smd rect
			(at -2.25 -3.125)
			(size 0.3 1.75)
			(layers "F.Cu" "F.Mask" "F.Paste")
			(net 1 "GND")
			(pinfunction "GND(FIXED)")
			(pintype "passive")
			(teardrops
				(best_length_ratio 0.2)
				(max_length 1)
				(best_width_ratio 0.9)
				(max_width 2)
				(curved_edges yes)
				(filter_ratio 0.9)
				(enabled yes)
				(allow_two_segments yes)
				(prefer_zone_connections yes)
			)
		)
		(pad "C52" smd rect
			(at -1.75 -3.125)
			(size 0.3 1.75)
			(layers "F.Cu" "F.Mask" "F.Paste")
			(net 532 "/Backplane/PCIe_{x2}.RX0+")
			(pinfunction "PCIE_RX16+")
			(pintype "input")
			(teardrops
				(best_length_ratio 0.2)
				(max_length 1)
				(best_width_ratio 0.9)
				(max_width 2)
				(curved_edges yes)
				(filter_ratio 0.9)
				(enabled yes)
				(allow_two_segments yes)
				(prefer_zone_connections yes)
			)
		)
		(pad "C53" smd rect
			(at -1.25 -3.125)
			(size 0.3 1.75)
			(layers "F.Cu" "F.Mask" "F.Paste")
			(net 537 "/Backplane/PCIe_{x2}.RX0-")
			(pinfunction "PCIE_RX16-")
			(pintype "input")
			(teardrops
				(best_length_ratio 0.2)
				(max_length 1)
				(best_width_ratio 0.9)
				(max_width 2)
				(curved_edges yes)
				(filter_ratio 0.9)
				(enabled yes)
				(allow_two_segments yes)
				(prefer_zone_connections yes)
			)
		)
		(pad "C54" smd rect
			(at -0.75 -3.125)
			(size 0.3 1.75)
			(layers "F.Cu" "F.Mask" "F.Paste")
			(net 136 "/Com Express 7 MGMT/~{TYPE0}")
			(pinfunction "~{TYPE0}")
			(pintype "passive")
			(teardrops
				(best_length_ratio 0.2)
				(max_length 1)
				(best_width_ratio 0.9)
				(max_width 2)
				(curved_edges yes)
				(filter_ratio 0.9)
				(enabled yes)
				(allow_two_segments yes)
				(prefer_zone_connections yes)
			)
		)
		(pad "C55" smd rect
			(at -0.25 -3.125)
			(size 0.3 1.75)
			(layers "F.Cu" "F.Mask" "F.Paste")
			(net 771 "/Backplane/PCIe_{x2}.RX1+")
			(pinfunction "PCIE_RX17+")
			(pintype "input")
			(teardrops
				(best_length_ratio 0.2)
				(max_length 1)
				(best_width_ratio 0.9)
				(max_width 2)
				(curved_edges yes)
				(filter_ratio 0.9)
				(enabled yes)
				(allow_two_segments yes)
				(prefer_zone_connections yes)
			)
		)
		(pad "C56" smd rect
			(at 0.25 -3.125)
			(size 0.3 1.75)
			(layers "F.Cu" "F.Mask" "F.Paste")
			(net 772 "/Backplane/PCIe_{x2}.RX1-")
			(pinfunction "PCIE_RX17-")
			(pintype "input")
			(teardrops
				(best_length_ratio 0.2)
				(max_length 1)
				(best_width_ratio 0.9)
				(max_width 2)
				(curved_edges yes)
				(filter_ratio 0.9)
				(enabled yes)
				(allow_two_segments yes)
				(prefer_zone_connections yes)
			)
		)
		(pad "C57" smd rect
			(at 0.75 -3.125)
			(size 0.3 1.75)
			(layers "F.Cu" "F.Mask" "F.Paste")
			(net 434 "/Com Express 7 MGMT/~{TYPE1}")
			(pinfunction "~{TYPE1}")
			(pintype "passive")
			(teardrops
				(best_length_ratio 0.2)
				(max_length 1)
				(best_width_ratio 0.9)
				(max_width 2)
				(curved_edges yes)
				(filter_ratio 0.9)
				(enabled yes)
				(allow_two_segments yes)
				(prefer_zone_connections yes)
			)
		)
		(pad "C58" smd rect
			(at 1.25 -3.125)
			(size 0.3 1.75)
			(layers "F.Cu" "F.Mask" "F.Paste")
			(net 881 "unconnected-(J12N-PCIE_RX18+-PadC58)")
			(pinfunction "PCIE_RX18+")
			(pintype "input+no_connect")
			(teardrops
				(best_length_ratio 0.2)
				(max_length 1)
				(best_width_ratio 0.9)
				(max_width 2)
				(curved_edges yes)
				(filter_ratio 0.9)
				(enabled yes)
				(allow_two_segments yes)
				(prefer_zone_connections yes)
			)
		)
		(pad "C59" smd rect
			(at 1.75 -3.125)
			(size 0.3 1.75)
			(layers "F.Cu" "F.Mask" "F.Paste")
			(net 882 "unconnected-(J12N-PCIE_RX18--PadC59)")
			(pinfunction "PCIE_RX18-")
			(pintype "input+no_connect")
			(teardrops
				(best_length_ratio 0.2)
				(max_length 1)
				(best_width_ratio 0.9)
				(max_width 2)
				(curved_edges yes)
				(filter_ratio 0.9)
				(enabled yes)
				(allow_two_segments yes)
				(prefer_zone_connections yes)
			)
		)
		(pad "C60" smd rect
			(at 2.25 -3.125)
			(size 0.3 1.75)
			(layers "F.Cu" "F.Mask" "F.Paste")
			(net 1 "GND")
			(pinfunction "GND(FIXED)")
			(pintype "passive")
			(teardrops
				(best_length_ratio 0.2)
				(max_length 1)
				(best_width_ratio 0.9)
				(max_width 2)
				(curved_edges yes)
				(filter_ratio 0.9)
				(enabled yes)
				(allow_two_segments yes)
				(prefer_zone_connections yes)
			)
		)
	)
)
